# S9S_MB_2U (Grand Teton) — schematic netlist excerpt (pin names and nets, part order shuffled) for the footprints in the layout excerpt that follows; sources: Cadence DE-HDL packaged netlist, KiCad conversion of 03242023_DA0F0TMBIJ0_F0T_Motherboard_J_brd_V01_OCP.brd

PC458_P1_2  Q_CAP  22UF 4V 20% X6S  pkg C0805  page 293 : A = PVCCINFAON_CPU1 ; B = GND
R195  Q_RES  49.9 1% CHIP  pkg 0402LF  page 123 : A = H_CPU_NMI_LVC1_N ; B = H_CPU0_NMI_LVC1_N

(kicad_pcb
	(version 20260206)
	(generator "pcbnew")
	(generator_version "10.0")
	(general
		(thickness 1.6)
		(legacy_teardrops no)
	)
	(paper "A4")
	(title_block
		(title "03242023_DA0F0TMBIJ0_F0T_Motherboard_J_brd_V01_OCP.brd")
		(comment 1 "Grand Teton / footprints 4464-4465 of 6105")
	)
	(layers
		(0 "F.Cu" signal "TOP")
		(4 "In1.Cu" signal "GND")
		(6 "In2.Cu" signal "IN1")
		(8 "In3.Cu" signal "GND1")
		(10 "In4.Cu" signal "IN2")
		(12 "In5.Cu" signal "GND2")
		(14 "In6.Cu" signal "IN3")
		(16 "In7.Cu" signal "GND3")
		(18 "In8.Cu" signal "VCC")
		(20 "In9.Cu" signal "VCC1")
		(22 "In10.Cu" signal "GND4")
		(24 "In11.Cu" signal "IN4")
		(26 "In12.Cu" signal "GND5")
		(28 "In13.Cu" signal "IN5")
		(30 "In14.Cu" signal "GND6")
		(32 "In15.Cu" signal "IN6")
		(34 "In16.Cu" signal "GND7")
		(2 "B.Cu" signal "BOTTOM")
		(9 "F.Adhes" user "F.Adhesive")
		(11 "B.Adhes" user "B.Adhesive")
		(13 "F.Paste" user "Package Geometry/Pastemask Top")
		(15 "B.Paste" user "Package Geometry/Pastemask Bottom")
		(5 "F.SilkS" user "Ref Des/Silkscreen Top")
		(7 "B.SilkS" user "Ref Des/Silkscreen Bottom")
		(1 "F.Mask" user "Board Geometry/Soldermask Top")
		(3 "B.Mask" user "Board Geometry/Soldermask Bottom")
		(17 "Dwgs.User" user "User.Drawings")
		(19 "Cmts.User" user "User.Comments")
		(21 "Eco1.User" user "User.Eco1")
		(23 "Eco2.User" user "User.Eco2")
		(25 "Edge.Cuts" user "Board Geometry/Outline")
		(27 "Margin" user)
		(31 "F.CrtYd" user "Package Geometry/Place Bound Top")
		(29 "B.CrtYd" user "Package Geometry/Place Bound Bottom")
		(35 "F.Fab" user "Ref Des/Assembly Top")
		(33 "B.Fab" user "Ref Des/Assembly Bottom")
	)
	(footprint ""
		(layer "B.Cu")
		(at 62.996572 -151.23668)
		(property "Reference" "PC458_P1_2"
			(at 0 0 0)
			(layer "B.SilkS")
			(hide yes)
			(effects
				(font
					(size 1.27 1.27)
				)
				(justify mirror)
			)
		)
		(property "Value" ""
			(at 0 0 0)
			(layer "B.Fab")
			(effects
				(font
					(size 1.27 1.27)
				)
				(justify mirror)
			)
		)
		(duplicate_pad_numbers_are_jumpers no)
		(fp_line
			(start -1.524 -0.762)
			(end -1.524 0.762)
			(stroke
				(width 0.1524)
				(type default)
			)
			(layer "B.SilkS")
		)
		(fp_line
			(start -1.524 0.762)
			(end 1.524 0.762)
			(stroke
				(width 0.1524)
				(type default)
			)
			(layer "B.SilkS")
		)
		(fp_line
			(start 1.524 -0.762)
			(end -1.524 -0.762)
			(stroke
				(width 0.1524)
				(type default)
			)
			(layer "B.SilkS")
		)
		(fp_line
			(start 1.524 0.762)
			(end 1.524 -0.762)
			(stroke
				(width 0.1524)
				(type default)
			)
			(layer "B.SilkS")
		)
		(fp_line
			(start -1.1049 -0.724916)
			(end 1.1049 -0.724916)
			(stroke
				(width 0.1)
				(type default)
			)
			(layer "B.Fab")
		)
		(fp_line
			(start -1.1049 0.724916)
			(end -1.1049 -0.724916)
			(stroke
				(width 0.1)
				(type default)
			)
			(layer "B.Fab")
		)
		(fp_line
			(start 1.1049 -0.724916)
			(end 1.1049 0.724916)
			(stroke
				(width 0.1)
				(type default)
			)
			(layer "B.Fab")
		)
		(fp_line
			(start 1.1049 0.724916)
			(end -1.1049 0.724916)
			(stroke
				(width 0.1)
				(type default)
			)
			(layer "B.Fab")
		)
		(pad "1" smd rect
			(at 0.889 0)
			(size 1.016 1.27)
			(layers "B.Cu" "B.Mask" "B.Paste")
			(net "PVCCINFAON_CPU1")
		)
		(pad "2" smd rect
			(at -0.889 0)
			(size 1.016 1.27)
			(layers "B.Cu" "B.Mask" "B.Paste")
			(net "GND")
		)
	)
	(footprint ""
		(layer "B.Cu")
		(at 319.073022 -185.96991 -90)
		(property "Reference" "R195"
			(at 0 0 90)
			(layer "B.SilkS")
			(hide yes)
			(effects
				(font
					(size 1.27 1.27)
				)
				(justify mirror)
			)
		)
		(property "Value" ""
			(at 0 0 90)
			(layer "B.Fab")
			(effects
				(font
					(size 1.27 1.27)
				)
				(justify mirror)
			)
		)
		(duplicate_pad_numbers_are_jumpers no)
		(fp_line
			(start -0.7874 0.4064)
			(end 0.7874 0.4064)
			(stroke
				(width 0.1524)
				(type default)
			)
			(layer "B.SilkS")
		)
		(fp_line
			(start 0.7874 0.4064)
			(end 0.7874 -0.4064)
			(stroke
				(width 0.1524)
				(type default)
			)
			(layer "B.SilkS")
		)
		(fp_line
			(start -0.7874 -0.4064)
			(end -0.7874 0.4064)
			(stroke
				(width 0.1524)
				(type default)
			)
			(layer "B.SilkS")
		)
		(fp_line
			(start 0.7874 -0.4064)
			(end -0.7874 -0.4064)
			(stroke
				(width 0.1524)
				(type default)
			)
			(layer "B.SilkS")
		)
		(fp_line
			(start -0.67945 0.3048)
			(end -0.120396 0.3048)
			(stroke
				(width 0.1)
				(type default)
			)
			(layer "B.Fab")
		)
		(fp_line
			(start -0.120396 0.3048)
			(end -0.120396 0.2794)
			(stroke
				(width 0.1)
				(type default)
			)
			(layer "B.Fab")
		)
		(fp_line
			(start 0.12065 0.3048)
			(end 0.67945 0.3048)
			(stroke
				(width 0.1)
				(type default)
			)
			(layer "B.Fab")
		)
		(fp_line
			(start 0.67945 0.3048)
			(end 0.67945 -0.305054)
			(stroke
				(width 0.1)
				(type default)
			)
			(layer "B.Fab")
		)
		(fp_line
			(start -0.120396 0.2794)
			(end 0.12065 0.2794)
			(stroke
				(width 0.1)
				(type default)
			)
			(layer "B.Fab")
		)
		(fp_line
			(start 0.12065 0.2794)
			(end 0.12065 0.3048)
			(stroke
				(width 0.1)
				(type default)
			)
			(layer "B.Fab")
		)
		(fp_line
			(start -0.12065 -0.2794)
			(end -0.12065 -0.3048)
			(stroke
				(width 0.1)
				(type default)
			)
			(layer "B.Fab")
		)
		(fp_line
			(start 0.12065 -0.2794)
			(end -0.12065 -0.2794)
			(stroke
				(width 0.1)
				(type default)
			)
			(layer "B.Fab")
		)
		(fp_line
			(start -0.67945 -0.3048)
			(end -0.67945 0.3048)
			(stroke
				(width 0.1)
				(type default)
			)
			(layer "B.Fab")
		)
		(fp_line
			(start -0.12065 -0.3048)
			(end -0.67945 -0.3048)
			(stroke
				(width 0.1)
				(type default)
			)
			(layer "B.Fab")
		)
		(fp_line
			(start 0.12065 -0.305054)
			(end 0.12065 -0.2794)
			(stroke
				(width 0.1)
				(type default)
			)
			(layer "B.Fab")
		)
		(fp_line
			(start 0.67945 -0.305054)
			(end 0.12065 -0.305054)
			(stroke
				(width 0.1)
				(type default)
			)
			(layer "B.Fab")
		)
		(pad "1" smd circle
			(at 0.40005 0 90)
			(size 0 0)
			(layers "B.Cu" "B.Mask" "B.Paste")
			(net "H_CPU_NMI_LVC1_N")
		)
		(pad "2" smd circle
			(at -0.40005 0 90)
			(size 0 0)
			(layers "B.Cu" "B.Mask" "B.Paste")
			(net "H_CPU0_NMI_LVC1_N")
		)
	)
)
